FILE_TYPE = MACRO_DRAWING;
SET COLOR_WIRE YELLOW;
SET COLOR_PROP ORANGE;
SET COLOR_DOT WHITE;
SET COLOR_ARC YELLOW;
SET COLOR_BODY GREEN;
SET COLOR_NOTE PURPLE;
SET PROP_DISPLAY VALUE;
SET PAGE_NUMBER P77;
FORCEADD Q_RES..2
R 2
(-5900 3950);
FORCEPROP 1 LAST LOCATION R702
J 2
(-5925 4100);
DISPLAY 0.489362 (-5925 4100);
PAINT SKYBLUE (-5925 4100);
FORCEPROP 0 LAST $SEC 1
J 0
(-5925 4125);
DISPLAY 0.680851 (-5925 4125);
PAINT MONO (-5925 4125);
DISPLAY INVISIBLE (-5925 4125);
FORCEPROP 0 LAST CDS_SEC 1
J 0
(-5925 4125);
DISPLAY 1.021277 (-5925 4125);
DISPLAY INVISIBLE (-5925 4125);
FORCEPROP 1 LASTPIN (-5900 4050) $PN 1
J 2
(-5905 4012);
DISPLAY 0.489362 (-5905 4012);
PAINT MONO (-5905 4012);
FORCEPROP 1 LASTPIN (-5900 3850) $PN 2
J 2
(-5905 3860);
DISPLAY 0.489362 (-5905 3860);
PAINT MONO (-5905 3860);
FORCEPROP 1 LAST WATTAGE 1/16W
J 2
(-5940 3950);
DISPLAY 0.489362 (-5940 3950);
PAINT SKYBLUE (-5940 3950);
FORCEPROP 1 LAST MATERIAL EMPTY
J 2
(-5940 3900);
DISPLAY 0.489362 (-5940 3900);
PAINT RED (-5940 3900);
FORCEPROP 1 LAST TOLERANCE 5%
J 2
(-5945 4000);
DISPLAY 0.489362 (-5945 4000);
PAINT SKYBLUE (-5945 4000);
FORCEPROP 1 LAST VALUE 10K
J 2
(-5945 4050);
DISPLAY 0.489362 (-5945 4050);
PAINT SKYBLUE (-5945 4050);
FORCEPROP 1 LAST PART_NUMBER TMP_QCS31002JB28
J 2
(-5950 3800);
DISPLAY 0.489362 (-5950 3800);
PAINT SKYBLUE (-5950 3800);
FORCEPROP 1 LAST PACK_TYPE 0402LF
J 2
(-5940 3850);
DISPLAY 0.489362 (-5940 3850);
PAINT SKYBLUE (-5940 3850);
FORCEPROP 2 LAST CDS_LIB pure_quanta
J 2
(-5900 3950);
DISPLAY INVISIBLE (-5900 3950);
FORCEPROP 1 LAST PATH I1
J 2
(-5950 4125);
DISPLAY 0.978723 (-5950 4125);
PAINT WHITE (-5950 4125);
DISPLAY INVISIBLE (-5950 4125);
FORCEADD UNIVERSAL_GND..1
(-4125 4375);
FORCEPROP 3 LASTPIN (-4125 4425) SIG_NAME GND\g
J 0
(-4115 4435);
DISPLAY 0.659574 (-4115 4435);
PAINT MONO (-4115 4435);
DISPLAY INVISIBLE (-4115 4435);
FORCEPROP 2 LAST CDS_LIB pure_quanta_power
J 0
(-4125 4375);
DISPLAY INVISIBLE (-4125 4375);
FORCEPROP 1 LAST PATH I10
J 0
(-4050 4375);
DISPLAY 0.872340 (-4050 4375);
PAINT AQUA (-4050 4375);
DISPLAY INVISIBLE (-4050 4375);
FORCEPROP 1 LAST HDL_POWER GND
J 1
(-4100 4300);
DISPLAY 0.872340 (-4100 4300);
PAINT GREEN (-4100 4300);
DISPLAY INVISIBLE (-4100 4300);
FORCEADD Q_CAP..1
(-4125 4575);
FORCEPROP 1 LAST LOCATION C223
J 0
(-4075 4725);
DISPLAY 0.489362 (-4075 4725);
PAINT SKYBLUE (-4075 4725);
FORCEPROP 2 LAST $SEC 1
J 0
(-4075 4775);
DISPLAY 0.680851 (-4075 4775);
PAINT MONO (-4075 4775);
DISPLAY INVISIBLE (-4075 4775);
FORCEPROP 2 LAST CDS_SEC 1
J 0
(-4075 4775);
DISPLAY 0.680851 (-4075 4775);
DISPLAY INVISIBLE (-4075 4775);
FORCEPROP 1 LASTPIN (-4125 4675) $PN 1
J 0
(-4115 4655);
DISPLAY 0.489362 (-4115 4655);
PAINT MONO (-4115 4655);
FORCEPROP 1 LASTPIN (-4125 4475) $PN 2
J 0
(-4115 4455);
DISPLAY 0.489362 (-4115 4455);
PAINT MONO (-4115 4455);
FORCEPROP 1 LAST MATERIAL X7R
J 0
(-4075 4525);
DISPLAY 0.489362 (-4075 4525);
PAINT SKYBLUE (-4075 4525);
FORCEPROP 1 LAST TOLERANCE 10%
J 0
(-4075 4575);
DISPLAY 0.489362 (-4075 4575);
PAINT SKYBLUE (-4075 4575);
FORCEPROP 1 LAST VALUE 0.1UF
J 0
(-4075 4675);
DISPLAY 0.489362 (-4075 4675);
PAINT SKYBLUE (-4075 4675);
FORCEPROP 1 LAST VOLTAGE 25V
J 0
(-4075 4625);
DISPLAY 0.489362 (-4075 4625);
PAINT SKYBLUE (-4075 4625);
FORCEPROP 1 LAST PACK_TYPE 0402
J 0
(-4075 4475);
DISPLAY 0.489362 (-4075 4475);
PAINT SKYBLUE (-4075 4475);
FORCEPROP 2 LAST CDS_LIB pure_quanta
J 0
(-4125 4575);
DISPLAY INVISIBLE (-4125 4575);
FORCEPROP 1 LAST PATH I11
J 0
(-4075 4725);
DISPLAY 0.978723 (-4075 4725);
PAINT WHITE (-4075 4725);
DISPLAY INVISIBLE (-4075 4725);
FORCEPROP 1 LAST PART_NUMBER CH4104K1B00
J 0
(-4075 4425);
DISPLAY 0.489362 (-4075 4425);
PAINT SKYBLUE (-4075 4425);
DISPLAY INVISIBLE (-4075 4425);
FORCEADD UNIVERSAL_POWER..1
R 2
(-4200 4900);
FORCEPROP 3 LASTPIN (-4200 4850) SIG_NAME P1V8_STBY\g
J 0
(-4190 4860);
DISPLAY 0.659574 (-4190 4860);
PAINT MONO (-4190 4860);
DISPLAY INVISIBLE (-4190 4860);
FORCEPROP 1 LAST HDL_POWER P1V8_STBY
J 1
(-4200 4950);
DISPLAY 0.489362 (-4200 4950);
PAINT GREEN (-4200 4950);
FORCEPROP 2 LAST CDS_LIB pure_quanta_power
J 0
(-4200 4900);
DISPLAY INVISIBLE (-4200 4900);
FORCEPROP 1 LAST PATH I12
J 2
(-4250 4925);
DISPLAY 0.872340 (-4250 4925);
PAINT AQUA (-4250 4925);
DISPLAY INVISIBLE (-4250 4925);
FORCEADD OFFPAGE..5
R 2
(-3375 4225);
FORCEPROP 2 LAST $XR0 176 
J 0
(-3186 4225);
DISPLAY 0.638298 (-3186 4225);
PAINT MONO (-3186 4225);
FORCEPROP 2 LAST CDS_LIB standard
J 0
(-3375 4225);
DISPLAY INVISIBLE (-3375 4225);
FORCEPROP 2 LAST BOM_COST SYS_CLOCK
J 2
(-3575 4325);
DISPLAY 0.808511 (-3575 4325);
DISPLAY INVISIBLE (-3575 4325);
FORCEPROP 1 LAST OFFPAGE TRUE
J 2
(-3700 4100);
DISPLAY 0.872340 (-3700 4100);
PAINT GREEN (-3700 4100);
DISPLAY INVISIBLE (-3700 4100);
FORCEPROP 1 LAST COMMENT_BODY TRUE
J 2
(-3475 4150);
DISPLAY 0.872340 (-3475 4150);
PAINT GREEN (-3475 4150);
DISPLAY INVISIBLE (-3475 4150);
FORCEPROP 2 LAST PATH I13
J 0
(-3200 4300);
DISPLAY 0.680851 (-3200 4300);
DISPLAY INVISIBLE (-3200 4300);
FORCEPROP 2 LAST ROOM DB2000_2_NVME
J 2
(-3575 4275);
DISPLAY 0.808511 (-3575 4275);
PAINT RED (-3575 4275);
DISPLAY INVISIBLE (-3575 4275);
FORCEADD OFFPAGE..5
R 2
(-3375 4325);
FORCEPROP 2 LAST $XR0 169 
J 0
(-3186 4325);
DISPLAY 0.638298 (-3186 4325);
PAINT MONO (-3186 4325);
FORCEPROP 2 LAST CDS_LIB standard
J 0
(-3375 4325);
DISPLAY INVISIBLE (-3375 4325);
FORCEPROP 2 LAST BOM_COST SYS_CLOCK
J 2
(-3575 4425);
DISPLAY 0.808511 (-3575 4425);
DISPLAY INVISIBLE (-3575 4425);
FORCEPROP 1 LAST OFFPAGE TRUE
J 2
(-3700 4200);
DISPLAY 0.872340 (-3700 4200);
PAINT GREEN (-3700 4200);
DISPLAY INVISIBLE (-3700 4200);
FORCEPROP 1 LAST COMMENT_BODY TRUE
J 2
(-3475 4250);
DISPLAY 0.872340 (-3475 4250);
PAINT GREEN (-3475 4250);
DISPLAY INVISIBLE (-3475 4250);
FORCEPROP 2 LAST PATH I14
J 0
(-3200 4400);
DISPLAY 0.680851 (-3200 4400);
DISPLAY INVISIBLE (-3200 4400);
FORCEPROP 2 LAST ROOM DB2000_2_NVME
J 2
(-3575 4375);
DISPLAY 0.808511 (-3575 4375);
PAINT RED (-3575 4375);
DISPLAY INVISIBLE (-3575 4375);
FORCEADD SN74LVC2G07DCKR..1
(-4675 4275);
FORCEPROP 1 LAST LOCATION U29
J 0
(-4850 4480);
DISPLAY 0.489362 (-4850 4480);
PAINT SKYBLUE (-4850 4480);
FORCEPROP 2 LAST $SEC 1
J 0
(-4850 4625);
DISPLAY 0.680851 (-4850 4625);
PAINT MONO (-4850 4625);
DISPLAY INVISIBLE (-4850 4625);
FORCEPROP 2 LAST CDS_SEC 1
J 0
(-4850 4625);
DISPLAY 0.680851 (-4850 4625);
DISPLAY INVISIBLE (-4850 4625);
FORCEPROP 2 LASTPIN (-5000 4325) $PN 1
J 2
(-5010 4335);
DISPLAY 0.489362 (-5010 4335);
PAINT MONO (-5010 4335);
FORCEPROP 2 LASTPIN (-4350 4325) $PN 6
J 0
(-4340 4335);
DISPLAY 0.489362 (-4340 4335);
PAINT MONO (-4340 4335);
FORCEPROP 2 LASTPIN (-5000 4225) $PN 3
J 2
(-5010 4235);
DISPLAY 0.489362 (-5010 4235);
PAINT MONO (-5010 4235);
FORCEPROP 2 LASTPIN (-4350 4225) $PN 4
J 0
(-4340 4235);
DISPLAY 0.489362 (-4340 4235);
PAINT MONO (-4340 4235);
FORCEPROP 2 LASTPIN (-5000 4275) $PN 2
J 2
(-5010 4285);
DISPLAY 0.489362 (-5010 4285);
PAINT MONO (-5010 4285);
FORCEPROP 2 LASTPIN (-4350 4275) $PN 5
J 0
(-4340 4285);
DISPLAY 0.489362 (-4340 4285);
PAINT MONO (-4340 4285);
FORCEPROP 1 LAST MATERIAL IC
J 0
(-4850 4385);
DISPLAY 0.489362 (-4850 4385);
PAINT SKYBLUE (-4850 4385);
FORCEPROP 2 LAST VALUE SN74LVC2G07DCKR
J 0
(-4850 4575);
DISPLAY 0.489362 (-4850 4575);
PAINT SKYBLUE (-4850 4575);
FORCEPROP 1 LAST PART_NUMBER AL002G07006
J 0
(-4850 4435);
DISPLAY 0.489362 (-4850 4435);
PAINT SKYBLUE (-4850 4435);
FORCEPROP 2 LAST PACK_TYPE SMLF
J 0
(-4850 4525);
DISPLAY 0.489362 (-4850 4525);
PAINT SKYBLUE (-4850 4525);
FORCEPROP 1 LAST NEEDS_NO_SIZE TRUE
J 0
(-4675 4275);
DISPLAY 0.468085 (-4675 4275);
PAINT GREEN (-4675 4275);
DISPLAY INVISIBLE (-4675 4275);
FORCEPROP 2 LAST CDS_LIB pure_quanta
J 0
(-4675 4275);
DISPLAY INVISIBLE (-4675 4275);
FORCEPROP 1 LAST PATH I15
J 0
(-4525 4380);
DISPLAY 0.723404 (-4525 4380);
PAINT GREEN (-4525 4380);
DISPLAY INVISIBLE (-4525 4380);
FORCEADD OFFPAGE..5
R 2
(-3325 2550);
FORCEPROP 2 LAST $XR0 186 
J 0
(-3136 2550);
DISPLAY 0.638298 (-3136 2550);
PAINT MONO (-3136 2550);
FORCEPROP 2 LAST BOM_COST SYS_CLOCK
J 2
(-3525 2650);
DISPLAY 0.808511 (-3525 2650);
DISPLAY INVISIBLE (-3525 2650);
FORCEPROP 2 LAST CDS_LIB standard
J 0
(-3325 2550);
DISPLAY INVISIBLE (-3325 2550);
FORCEPROP 1 LAST OFFPAGE TRUE
J 2
(-3650 2425);
DISPLAY 0.872340 (-3650 2425);
PAINT GREEN (-3650 2425);
DISPLAY INVISIBLE (-3650 2425);
FORCEPROP 1 LAST COMMENT_BODY TRUE
J 2
(-3425 2475);
DISPLAY 0.872340 (-3425 2475);
PAINT GREEN (-3425 2475);
DISPLAY INVISIBLE (-3425 2475);
FORCEPROP 2 LAST PATH I16
J 0
(-3150 2625);
DISPLAY 0.680851 (-3150 2625);
DISPLAY INVISIBLE (-3150 2625);
FORCEPROP 2 LAST ROOM DB2000_2_NVME
J 2
(-3525 2600);
DISPLAY 0.808511 (-3525 2600);
PAINT RED (-3525 2600);
DISPLAY INVISIBLE (-3525 2600);
FORCEADD OFFPAGE..5
R 2
(-3325 2450);
FORCEPROP 2 LAST $XR0 193 
J 0
(-3136 2450);
DISPLAY 0.638298 (-3136 2450);
PAINT MONO (-3136 2450);
FORCEPROP 2 LAST BOM_COST SYS_CLOCK
J 2
(-3525 2550);
DISPLAY 0.808511 (-3525 2550);
DISPLAY INVISIBLE (-3525 2550);
FORCEPROP 2 LAST CDS_LIB standard
J 0
(-3325 2450);
DISPLAY INVISIBLE (-3325 2450);
FORCEPROP 1 LAST OFFPAGE TRUE
J 2
(-3650 2325);
DISPLAY 0.872340 (-3650 2325);
PAINT GREEN (-3650 2325);
DISPLAY INVISIBLE (-3650 2325);
FORCEPROP 1 LAST COMMENT_BODY TRUE
J 2
(-3425 2375);
DISPLAY 0.872340 (-3425 2375);
PAINT GREEN (-3425 2375);
DISPLAY INVISIBLE (-3425 2375);
FORCEPROP 2 LAST PATH I17
J 0
(-3150 2525);
DISPLAY 0.680851 (-3150 2525);
DISPLAY INVISIBLE (-3150 2525);
FORCEPROP 2 LAST ROOM DB2000_2_NVME
J 2
(-3525 2500);
DISPLAY 0.808511 (-3525 2500);
PAINT RED (-3525 2500);
DISPLAY INVISIBLE (-3525 2500);
FORCEADD Q_CAP..1
(-4075 2800);
FORCEPROP 1 LAST LOCATION C224
J 0
(-4025 2950);
DISPLAY 0.489362 (-4025 2950);
PAINT SKYBLUE (-4025 2950);
FORCEPROP 2 LAST $SEC 1
J 0
(-4025 3000);
DISPLAY 0.680851 (-4025 3000);
PAINT MONO (-4025 3000);
DISPLAY INVISIBLE (-4025 3000);
FORCEPROP 2 LAST CDS_SEC 1
J 0
(-4025 3000);
DISPLAY 0.680851 (-4025 3000);
DISPLAY INVISIBLE (-4025 3000);
FORCEPROP 1 LASTPIN (-4075 2900) $PN 1
J 0
(-4065 2880);
DISPLAY 0.489362 (-4065 2880);
PAINT MONO (-4065 2880);
FORCEPROP 1 LASTPIN (-4075 2700) $PN 2
J 0
(-4065 2680);
DISPLAY 0.489362 (-4065 2680);
PAINT MONO (-4065 2680);
FORCEPROP 1 LAST MATERIAL X7R
J 0
(-4025 2750);
DISPLAY 0.489362 (-4025 2750);
PAINT SKYBLUE (-4025 2750);
FORCEPROP 1 LAST TOLERANCE 10%
J 0
(-4025 2800);
DISPLAY 0.489362 (-4025 2800);
PAINT SKYBLUE (-4025 2800);
FORCEPROP 1 LAST VALUE 0.1UF
J 0
(-3850 2950);
DISPLAY 0.489362 (-3850 2950);
PAINT SKYBLUE (-3850 2950);
FORCEPROP 1 LAST VOLTAGE 25V
J 0
(-4025 2850);
DISPLAY 0.489362 (-4025 2850);
PAINT SKYBLUE (-4025 2850);
FORCEPROP 1 LAST PACK_TYPE 0402
J 0
(-4025 2700);
DISPLAY 0.489362 (-4025 2700);
PAINT SKYBLUE (-4025 2700);
FORCEPROP 2 LAST CDS_LIB pure_quanta
J 0
(-4075 2800);
DISPLAY INVISIBLE (-4075 2800);
FORCEPROP 1 LAST PATH I19
J 0
(-4025 2950);
DISPLAY 0.978723 (-4025 2950);
PAINT WHITE (-4025 2950);
DISPLAY INVISIBLE (-4025 2950);
FORCEPROP 1 LAST PART_NUMBER CH4104K1B00
J 0
(-4025 2650);
DISPLAY 0.489362 (-4025 2650);
PAINT SKYBLUE (-4025 2650);
DISPLAY INVISIBLE (-4025 2650);
FORCEADD GND..1
(-5900 3675);
FORCEPROP 3 LASTPIN (-5900 3725) SIG_NAME GND\g
J 0
(-5890 3735);
DISPLAY 0.659574 (-5890 3735);
PAINT MONO (-5890 3735);
DISPLAY INVISIBLE (-5890 3735);
FORCEPROP 2 LAST CDS_LIB pure_quanta_power
J 0
(-5900 3675);
DISPLAY INVISIBLE (-5900 3675);
FORCEPROP 1 LAST SIZE 1B
J 0
(-5825 3625);
DISPLAY 0.851064 (-5825 3625);
PAINT GREEN (-5825 3625);
DISPLAY INVISIBLE (-5825 3625);
FORCEPROP 2 LAST BOM_COST MEM
J 0
(-6000 3750);
DISPLAY 0.808511 (-6000 3750);
DISPLAY INVISIBLE (-6000 3750);
FORCEPROP 1 LAST PATH I2
J 0
(-5825 3675);
DISPLAY 0.872340 (-5825 3675);
PAINT AQUA (-5825 3675);
DISPLAY INVISIBLE (-5825 3675);
FORCEPROP 1 LAST HDL_POWER GND
J 0
(-5900 3825);
DISPLAY 0.851064 (-5900 3825);
PAINT GREEN (-5900 3825);
DISPLAY INVISIBLE (-5900 3825);
FORCEADD UNIVERSAL_GND..1
(-4075 2600);
FORCEPROP 3 LASTPIN (-4075 2650) SIG_NAME GND\g
J 0
(-4065 2660);
DISPLAY 0.659574 (-4065 2660);
PAINT MONO (-4065 2660);
DISPLAY INVISIBLE (-4065 2660);
FORCEPROP 2 LAST CDS_LIB pure_quanta_power
J 0
(-4075 2600);
DISPLAY INVISIBLE (-4075 2600);
FORCEPROP 1 LAST PATH I20
J 0
(-4000 2600);
DISPLAY 0.872340 (-4000 2600);
PAINT AQUA (-4000 2600);
DISPLAY INVISIBLE (-4000 2600);
FORCEPROP 1 LAST HDL_POWER GND
J 1
(-4050 2525);
DISPLAY 0.872340 (-4050 2525);
PAINT GREEN (-4050 2525);
DISPLAY INVISIBLE (-4050 2525);
FORCEADD SN74LVC2G07DCKR..1
(-4625 2500);
FORCEPROP 1 LAST LOCATION U40
J 0
(-4800 2705);
DISPLAY 0.489362 (-4800 2705);
PAINT SKYBLUE (-4800 2705);
FORCEPROP 2 LAST $SEC 1
J 0
(-4800 2850);
DISPLAY 0.680851 (-4800 2850);
PAINT MONO (-4800 2850);
DISPLAY INVISIBLE (-4800 2850);
FORCEPROP 2 LAST CDS_SEC 1
J 0
(-4800 2850);
DISPLAY 0.680851 (-4800 2850);
DISPLAY INVISIBLE (-4800 2850);
FORCEPROP 2 LASTPIN (-4950 2550) $PN 1
J 2
(-4960 2560);
DISPLAY 0.489362 (-4960 2560);
PAINT MONO (-4960 2560);
FORCEPROP 2 LASTPIN (-4300 2550) $PN 6
J 0
(-4290 2560);
DISPLAY 0.489362 (-4290 2560);
PAINT MONO (-4290 2560);
FORCEPROP 2 LASTPIN (-4950 2450) $PN 3
J 2
(-4960 2460);
DISPLAY 0.489362 (-4960 2460);
PAINT MONO (-4960 2460);
FORCEPROP 2 LASTPIN (-4300 2450) $PN 4
J 0
(-4290 2460);
DISPLAY 0.489362 (-4290 2460);
PAINT MONO (-4290 2460);
FORCEPROP 2 LASTPIN (-4950 2500) $PN 2
J 2
(-4960 2510);
DISPLAY 0.489362 (-4960 2510);
PAINT MONO (-4960 2510);
FORCEPROP 2 LASTPIN (-4300 2500) $PN 5
J 0
(-4290 2510);
DISPLAY 0.489362 (-4290 2510);
PAINT MONO (-4290 2510);
FORCEPROP 1 LAST MATERIAL IC
J 0
(-4800 2610);
DISPLAY 0.489362 (-4800 2610);
PAINT SKYBLUE (-4800 2610);
FORCEPROP 2 LAST VALUE SN74LVC2G07DCKR
J 0
(-4800 2800);
DISPLAY 0.489362 (-4800 2800);
PAINT SKYBLUE (-4800 2800);
FORCEPROP 1 LAST PART_NUMBER AL002G07006
J 0
(-4800 2660);
DISPLAY 0.489362 (-4800 2660);
PAINT SKYBLUE (-4800 2660);
FORCEPROP 2 LAST PACK_TYPE SMLF
J 0
(-4800 2750);
DISPLAY 0.489362 (-4800 2750);
PAINT SKYBLUE (-4800 2750);
FORCEPROP 1 LAST NEEDS_NO_SIZE TRUE
J 0
(-4625 2500);
DISPLAY 0.468085 (-4625 2500);
PAINT GREEN (-4625 2500);
DISPLAY INVISIBLE (-4625 2500);
FORCEPROP 2 LAST CDS_LIB pure_quanta
J 0
(-4625 2500);
DISPLAY INVISIBLE (-4625 2500);
FORCEPROP 1 LAST PATH I21
J 0
(-4475 2605);
DISPLAY 0.723404 (-4475 2605);
PAINT GREEN (-4475 2605);
DISPLAY INVISIBLE (-4475 2605);
FORCEADD UNIVERSAL_GND..1
R 5
(-5050 2500);
FORCEPROP 3 LASTPIN (-5000 2500) SIG_NAME GND\g
J 0
(-4990 2510);
DISPLAY 0.659574 (-4990 2510);
PAINT MONO (-4990 2510);
DISPLAY INVISIBLE (-4990 2510);
FORCEPROP 2 LAST CDS_LIB pure_quanta_power
J 0
(-5050 2500);
DISPLAY INVISIBLE (-5050 2500);
FORCEPROP 1 LAST PATH I22
R 3
J 0
(-5050 2425);
DISPLAY 0.872340 (-5050 2425);
PAINT AQUA (-5050 2425);
DISPLAY INVISIBLE (-5050 2425);
FORCEPROP 1 LAST HDL_POWER GND
R 3
J 1
(-5125 2475);
DISPLAY 0.872340 (-5125 2475);
PAINT GREEN (-5125 2475);
DISPLAY INVISIBLE (-5125 2475);
FORCEADD UNIVERSAL_POWER..1
R 2
(-4150 3125);
FORCEPROP 3 LASTPIN (-4150 3075) SIG_NAME P1V8_STBY\g
J 0
(-4140 3085);
DISPLAY 0.659574 (-4140 3085);
PAINT MONO (-4140 3085);
DISPLAY INVISIBLE (-4140 3085);
FORCEPROP 1 LAST HDL_POWER P1V8_STBY
J 1
(-4150 3175);
DISPLAY 0.489362 (-4150 3175);
PAINT GREEN (-4150 3175);
FORCEPROP 2 LAST CDS_LIB pure_quanta_power
J 0
(-4150 3125);
DISPLAY INVISIBLE (-4150 3125);
FORCEPROP 1 LAST PATH I23
J 2
(-4200 3150);
DISPLAY 0.872340 (-4200 3150);
PAINT AQUA (-4200 3150);
DISPLAY INVISIBLE (-4200 3150);
FORCEADD OFFPAGE..1
(-6000 4325);
FORCEPROP 2 LAST $XR2 84 
J 0
(-6431 4325);
DISPLAY 0.638298 (-6431 4325);
PAINT MONO (-6431 4325);
FORCEPROP 2 LAST $XR1 80 
J 0
(-6341 4325);
DISPLAY 0.638298 (-6341 4325);
PAINT MONO (-6341 4325);
FORCEPROP 2 LAST $XR0 28 
J 0
(-6251 4325);
DISPLAY 0.638298 (-6251 4325);
PAINT MONO (-6251 4325);
FORCEPROP 1 LAST OFFPAGE TRUE
J 0
(-5675 4200);
DISPLAY 0.872340 (-5675 4200);
PAINT GREEN (-5675 4200);
DISPLAY INVISIBLE (-5675 4200);
FORCEPROP 1 LAST COMMENT_BODY TRUE
J 0
(-5875 4225);
DISPLAY 0.872340 (-5875 4225);
PAINT GREEN (-5875 4225);
DISPLAY INVISIBLE (-5875 4225);
FORCEPROP 2 LAST PATH I3
J 0
(-6200 4375);
DISPLAY 0.680851 (-6200 4375);
DISPLAY INVISIBLE (-6200 4375);
FORCEPROP 2 LAST CDS_LIB standard
J 0
(-6000 4325);
DISPLAY INVISIBLE (-6000 4325);
FORCEADD OFFPAGE..1
(-5950 2550);
FORCEPROP 2 LAST $XR2 84 
J 0
(-6351 2550);
DISPLAY 0.638298 (-6351 2550);
PAINT MONO (-6351 2550);
FORCEPROP 2 LAST $XR1 80 
J 0
(-6261 2550);
DISPLAY 0.638298 (-6261 2550);
PAINT MONO (-6261 2550);
FORCEPROP 2 LAST $XR0 55 
J 0
(-6171 2550);
DISPLAY 0.638298 (-6171 2550);
PAINT MONO (-6171 2550);
FORCEPROP 1 LAST OFFPAGE TRUE
J 0
(-5625 2425);
DISPLAY 0.872340 (-5625 2425);
PAINT GREEN (-5625 2425);
DISPLAY INVISIBLE (-5625 2425);
FORCEPROP 1 LAST COMMENT_BODY TRUE
J 0
(-5825 2450);
DISPLAY 0.872340 (-5825 2450);
PAINT GREEN (-5825 2450);
DISPLAY INVISIBLE (-5825 2450);
FORCEPROP 2 LAST PATH I4
J 0
(-5900 2625);
DISPLAY 0.680851 (-5900 2625);
DISPLAY INVISIBLE (-5900 2625);
FORCEPROP 2 LAST CDS_LIB standard
J 0
(-5950 2550);
DISPLAY INVISIBLE (-5950 2550);
FORCEADD Q_RES..2
R 2
(-5850 2175);
FORCEPROP 1 LAST LOCATION R703
J 2
(-5895 2300);
DISPLAY 0.489362 (-5895 2300);
PAINT SKYBLUE (-5895 2300);
FORCEPROP 2 LAST $SEC 1
J 0
(-5900 2400);
DISPLAY 0.680851 (-5900 2400);
PAINT MONO (-5900 2400);
DISPLAY INVISIBLE (-5900 2400);
FORCEPROP 2 LAST CDS_SEC 1
J 0
(-5900 2400);
DISPLAY 0.680851 (-5900 2400);
DISPLAY INVISIBLE (-5900 2400);
FORCEPROP 1 LASTPIN (-5850 2275) $PN 1
J 2
(-5855 2237);
DISPLAY 0.489362 (-5855 2237);
PAINT MONO (-5855 2237);
FORCEPROP 1 LASTPIN (-5850 2075) $PN 2
J 2
(-5855 2085);
DISPLAY 0.489362 (-5855 2085);
PAINT MONO (-5855 2085);
FORCEPROP 1 LAST WATTAGE 1/16W
J 2
(-5890 2175);
DISPLAY 0.489362 (-5890 2175);
PAINT SKYBLUE (-5890 2175);
FORCEPROP 1 LAST MATERIAL EMPTY
J 2
(-5890 2125);
DISPLAY 0.489362 (-5890 2125);
PAINT RED (-5890 2125);
FORCEPROP 1 LAST TOLERANCE 5%
J 2
(-5895 2225);
DISPLAY 0.489362 (-5895 2225);
PAINT SKYBLUE (-5895 2225);
FORCEPROP 1 LAST VALUE 10K
J 2
(-5895 2275);
DISPLAY 0.489362 (-5895 2275);
PAINT SKYBLUE (-5895 2275);
FORCEPROP 1 LAST PART_NUMBER TMP_QCS31002JB28
J 2
(-5900 2025);
DISPLAY 0.489362 (-5900 2025);
PAINT SKYBLUE (-5900 2025);
FORCEPROP 1 LAST PACK_TYPE 0402LF
J 2
(-5890 2075);
DISPLAY 0.489362 (-5890 2075);
PAINT SKYBLUE (-5890 2075);
FORCEPROP 2 LAST CDS_LIB pure_quanta
J 0
(-5850 2175);
DISPLAY INVISIBLE (-5850 2175);
FORCEPROP 1 LAST PATH I5
J 2
(-5900 2350);
DISPLAY 0.978723 (-5900 2350);
PAINT WHITE (-5900 2350);
DISPLAY INVISIBLE (-5900 2350);
FORCEADD GND..1
(-5850 1900);
FORCEPROP 3 LASTPIN (-5850 1950) SIG_NAME GND\g
J 0
(-5840 1960);
DISPLAY 0.659574 (-5840 1960);
PAINT MONO (-5840 1960);
DISPLAY INVISIBLE (-5840 1960);
FORCEPROP 1 LAST SIZE 1B
J 0
(-5775 1850);
DISPLAY 0.851064 (-5775 1850);
PAINT GREEN (-5775 1850);
DISPLAY INVISIBLE (-5775 1850);
FORCEPROP 2 LAST BOM_COST MEM
J 0
(-5950 1975);
DISPLAY 0.808511 (-5950 1975);
DISPLAY INVISIBLE (-5950 1975);
FORCEPROP 2 LAST CDS_LIB pure_quanta_power
J 0
(-5850 1900);
DISPLAY INVISIBLE (-5850 1900);
FORCEPROP 1 LAST PATH I6
J 0
(-5775 1900);
DISPLAY 0.872340 (-5775 1900);
PAINT AQUA (-5775 1900);
DISPLAY INVISIBLE (-5775 1900);
FORCEPROP 1 LAST HDL_POWER GND
J 0
(-5850 2050);
DISPLAY 0.851064 (-5850 2050);
PAINT GREEN (-5850 2050);
DISPLAY INVISIBLE (-5850 2050);
FORCEADD UNIVERSAL_GND..1
R 5
(-5100 4275);
FORCEPROP 3 LASTPIN (-5050 4275) SIG_NAME GND\g
J 0
(-5040 4285);
DISPLAY 0.659574 (-5040 4285);
PAINT MONO (-5040 4285);
DISPLAY INVISIBLE (-5040 4285);
FORCEPROP 2 LAST CDS_LIB pure_quanta_power
J 0
(-5100 4275);
DISPLAY INVISIBLE (-5100 4275);
FORCEPROP 1 LAST PATH I9
R 3
J 0
(-5100 4200);
DISPLAY 0.872340 (-5100 4200);
PAINT AQUA (-5100 4200);
DISPLAY INVISIBLE (-5100 4200);
FORCEPROP 1 LAST HDL_POWER GND
R 3
J 1
(-5175 4250);
DISPLAY 0.872340 (-5175 4250);
PAINT GREEN (-5175 4250);
DISPLAY INVISIBLE (-5175 4250);
FORCEADD DNS..2
(-5900 3875);
PAINT RED (-5900 3875);
FORCEPROP 2 LAST CDS_LIB mstr_misc
J 0
(-5900 3875);
DISPLAY INVISIBLE (-5900 3875);
FORCEPROP 1 LAST COMMENT_BODY TRUE
J 0
(-5900 3875);
PAINT RED (-5900 3875);
DISPLAY INVISIBLE (-5900 3875);
FORCEADD QUANTA_TITLE_BLOCK_C..1
(0 0);
FORCEPROP 0 LAST CDS_CON_LAST_MODIFIED Fri Mar 11 14:52:49 2022
J 0
(-1885 15);
DISPLAY INVISIBLE (-1885 15);
FORCEPROP 1 LAST CUSTOM_TXT_CDS <CON_LAST_MODIFIED>
J 0
(-1885 15);
DISPLAY 0.978723 (-1885 15);
FORCEPROP 2 LAST CUSTOM_TXT_CDS <XR_PAGE_TITLE>
J 0
(-7890 5250);
DISPLAY 0.638298 (-7890 5250);
PAINT PINK (-7890 5250);
DISPLAY INVISIBLE (-7890 5250);
FORCEPROP 1 LAST CUSTOM_TXT_CDS <NAME_2>
J 0
(-3175 50);
FORCEPROP 1 LAST CUSTOM_TXT_CDS <NAME_1>
J 0
(-3175 175);
FORCEPROP 1 LAST CUSTOM_TXT_CDS <Q_NUMBER>
J 0
(-1403 103);
DISPLAY 1.212766 (-1403 103);
FORCEPROP 1 LAST CUSTOM_TXT_CDS <Q_PROJ>
J 0
(-2382 102);
DISPLAY 1.212766 (-2382 102);
FORCEPROP 1 LAST CUSTOM_TXT_CDS <Q_REV>
J 0
(-184 103);
DISPLAY 1.212766 (-184 103);
FORCEPROP 1 LAST CUSTOM_TXT_CDS <CON_PAGE_NUM> OF <CON_TOTAL_PAGES>
J 0
(-446 18);
DISPLAY 0.978723 (-446 18);
FORCEPROP 1 LAST Q_TITLE CPU PWROK
J 0
(-9300 50);
DISPLAY 2.446809 (-9300 50);
PAINT GREEN (-9300 50);
FORCEPROP 1 LAST Q_DEPT BU9
J 1
(-3763 49);
DISPLAY 1.957447 (-3763 49);
PAINT GREEN (-3763 49);
FORCEPROP 1 LAST CDS_LMAN_SYM_OUTLINE -9475,6775,100,-125
J 0
(0 0);
DISPLAY 0.468085 (0 0);
PAINT GREEN (0 0);
DISPLAY INVISIBLE (0 0);
FORCEPROP 2 LAST CDS_LIB pure_quanta
J 0
(0 0);
DISPLAY INVISIBLE (0 0);
FORCEPROP 2 LAST PAGE_BORDER TRUE
J 0
(-7890 5250);
DISPLAY 0.638298 (-7890 5250);
PAINT PINK (-7890 5250);
DISPLAY INVISIBLE (-7890 5250);
FORCEPROP 1 LAST COMMENT_BODY TRUE
J 0
(12 -13);
DISPLAY 0.978723 (12 -13);
PAINT GREEN (12 -13);
DISPLAY INVISIBLE (12 -13);
FORCEPROP 2 LAST CDS_XR_PAGE_TITLE CR-77 : @T6G_MB_LIB.T6G(SCH_1):PAGE77
J 0
(-7890 5250);
DISPLAY 0.638298 (-7890 5250);
PAINT PINK (-7890 5250);
DISPLAY INVISIBLE (-7890 5250);
FORCEADD DNS..2
(-5825 2100);
PAINT RED (-5825 2100);
FORCEPROP 2 LAST CDS_LIB mstr_misc
J 0
(-5825 2100);
DISPLAY INVISIBLE (-5825 2100);
FORCEPROP 1 LAST COMMENT_BODY TRUE
J 0
(-5825 2100);
PAINT RED (-5825 2100);
DISPLAY INVISIBLE (-5825 2100);
WIRE 16 -1 (-4125 4475)(-4125 4425);
WIRE 16 -1 (-5900 3850)(-5900 3725);
WIRE 16 -1 (-4075 2700)(-4075 2650);
WIRE 16 -1 (-5000 2500)(-4950 2500);
WIRE 16 -1 (-5850 2075)(-5850 1950);
WIRE 16 -1 (-5050 4275)(-5000 4275);
WIRE 16 -1 (-5850 2550)(-5225 2550);
WIRE 16 -1 (-5850 2275)(-5850 2550);
FORCEPROP 2 LAST SIG_NAME PWRGD_CPU1_PWROK
J 0
(-5810 2560);
DISPLAY 0.489362 (-5810 2560);
WIRE 16 -1 (-5850 2550)(-5900 2550);
WIRE 16 -1 (-5225 2550)(-4950 2550);
WIRE 16 -1 (-5225 2550)(-5225 2450);
WIRE 16 -1 (-5225 2450)(-4950 2450);
WIRE 16 -1 (-4300 2500)(-4150 2500);
WIRE 16 -1 (-4150 2975)(-4150 2500);
WIRE 16 -1 (-4075 2975)(-4150 2975);
WIRE 16 -1 (-4150 3075)(-4150 2975);
WIRE 16 -1 (-4075 2900)(-4075 2975);
WIRE 16 -1 (-5900 4050)(-5900 4325);
FORCEPROP 2 LAST SIG_NAME PWRGD_CPU0_PWROK
J 0
(-5910 4335);
DISPLAY 0.489362 (-5910 4335);
WIRE 16 -1 (-5275 4325)(-5900 4325);
WIRE 16 -1 (-5900 4325)(-5950 4325);
WIRE 16 -1 (-5000 4325)(-5275 4325);
WIRE 16 -1 (-5275 4325)(-5275 4225);
WIRE 16 -1 (-5275 4225)(-5000 4225);
WIRE 16 -1 (-4350 4275)(-4200 4275);
WIRE 16 -1 (-4200 4750)(-4200 4275);
WIRE 16 -1 (-4200 4850)(-4200 4750);
WIRE 16 -1 (-4125 4750)(-4200 4750);
WIRE 16 -1 (-4125 4675)(-4125 4750);
WIRE 16 -1 (-3425 4225)(-4350 4225);
FORCEPROP 2 LAST SIG_NAME PVDDCR_CPU1_P0_RESET_N
J 0
(-4060 4235);
DISPLAY 0.489362 (-4060 4235);
WIRE 16 -1 (-3425 4325)(-4350 4325);
FORCEPROP 2 LAST SIG_NAME PVDDCR_CPU0_P0_RESET_N
J 0
(-4060 4335);
DISPLAY 0.489362 (-4060 4335);
WIRE 16 -1 (-4300 2550)(-3375 2550);
FORCEPROP 2 LAST SIG_NAME PVDDCR_CPU0_P1_RESET_N
J 0
(-3885 2560);
DISPLAY 0.489362 (-3885 2560);
WIRE 16 -1 (-4300 2450)(-3375 2450);
FORCEPROP 2 LAST SIG_NAME PVDDCR_CPU1_P1_RESET_N
J 0
(-3885 2460);
DISPLAY 0.489362 (-3885 2460);
DOT 1 (-5850 2550);
DOT 1 (-4150 2975);
DOT 1 (-5225 2550);
DOT 1 (-5900 4325);
DOT 1 (-5275 4325);
DOT 1 (-4200 4750);
FORCENOTE
PWROK TO VR RST
(-8025 5950) 0;
DISPLAY LEFT (-8025 5950);
DISPLAY 5.170213 (-8025 5950);
PAINT WHITE (-8025 5950);
FORCENOTE
VID:VDDCR_CPU*/VDDCR_SOC/VDDIO
(-8025 5600) 0;
DISPLAY LEFT (-8025 5600);
DISPLAY 5.170213 (-8025 5600);
PAINT WHITE (-8025 5600);
QUIT
